(kicad_pcb
	(version 20260206)
	(generator "pcbnew")
	(generator_version "10.0")
	(general
		(thickness 1.6)
		(legacy_teardrops no)
	)
	(paper "A4")
	(title_block
		(title "01162023_DA0F0TEBIF0_F0T_Expander_BD_F_brd_V02_OCP.brd")
		(comment 1 "Grand Teton / footprints 4508-4512 of 9728")
	)
	(layers
		(0 "F.Cu" signal "TOP")
		(4 "In1.Cu" signal "GND")
		(6 "In2.Cu" signal "VCC")
		(8 "In3.Cu" signal "VCC1")
		(10 "In4.Cu" signal "GND1")
		(12 "In5.Cu" signal "IN1")
		(14 "In6.Cu" signal "GND2")
		(16 "In7.Cu" signal "IN2")
		(18 "In8.Cu" signal "GND3")
		(20 "In9.Cu" signal "IN3")
		(22 "In10.Cu" signal "GND4")
		(24 "In11.Cu" signal "IN4")
		(26 "In12.Cu" signal "GND5")
		(28 "In13.Cu" signal "IN5")
		(30 "In14.Cu" signal "GND6")
		(32 "In15.Cu" signal "IN6")
		(34 "In16.Cu" signal "GND7")
		(2 "B.Cu" signal "BOTTOM")
		(9 "F.Adhes" user "F.Adhesive")
		(11 "B.Adhes" user "B.Adhesive")
		(13 "F.Paste" user "Package Geometry/Pastemask Top")
		(15 "B.Paste" user "Package Geometry/Pastemask Bottom")
		(5 "F.SilkS" user "Ref Des/Silkscreen Top")
		(7 "B.SilkS" user "Ref Des/Silkscreen Bottom")
		(1 "F.Mask" user "Board Geometry/Soldermask Top")
		(3 "B.Mask" user "Board Geometry/Soldermask Bottom")
		(17 "Dwgs.User" user "User.Drawings")
		(19 "Cmts.User" user "User.Comments")
		(21 "Eco1.User" user "User.Eco1")
		(23 "Eco2.User" user "User.Eco2")
		(25 "Edge.Cuts" user "Board Geometry/Outline")
		(27 "Margin" user)
		(31 "F.CrtYd" user "Package Geometry/Place Bound Top")
		(29 "B.CrtYd" user "Package Geometry/Place Bound Bottom")
		(35 "F.Fab" user "Ref Des/Assembly Top")
		(33 "B.Fab" user "Ref Des/Assembly Bottom")
	)
	(footprint ""
		(layer "F.Cu")
		(at 347.683836 -279.486868 -90)
		(property "Reference" "PR155"
			(at 0 0 270)
			(layer "F.SilkS")
			(hide yes)
			(effects
				(font
					(size 1.27 1.27)
				)
			)
		)
		(property "Value" ""
			(at 0 0 270)
			(layer "F.Fab")
			(effects
				(font
					(size 1.27 1.27)
				)
			)
		)
		(duplicate_pad_numbers_are_jumpers no)
		(fp_line
			(start -0.7874 0.4064)
			(end -0.7874 -0.4064)
			(stroke
				(width 0.1524)
				(type default)
			)
			(layer "F.SilkS")
		)
		(fp_line
			(start 0.7874 0.4064)
			(end -0.7874 0.4064)
			(stroke
				(width 0.1524)
				(type default)
			)
			(layer "F.SilkS")
		)
		(fp_line
			(start -0.7874 -0.4064)
			(end 0.7874 -0.4064)
			(stroke
				(width 0.1524)
				(type default)
			)
			(layer "F.SilkS")
		)
		(fp_line
			(start 0.7874 -0.4064)
			(end 0.7874 0.4064)
			(stroke
				(width 0.1524)
				(type default)
			)
			(layer "F.SilkS")
		)
		(fp_line
			(start -0.67945 0.3048)
			(end -0.67945 -0.305054)
			(stroke
				(width 0.1)
				(type default)
			)
			(layer "F.Fab")
		)
		(fp_line
			(start -0.12065 0.3048)
			(end -0.67945 0.3048)
			(stroke
				(width 0.1)
				(type default)
			)
			(layer "F.Fab")
		)
		(fp_line
			(start 0.120396 0.3048)
			(end 0.120396 0.2794)
			(stroke
				(width 0.1)
				(type default)
			)
			(layer "F.Fab")
		)
		(fp_line
			(start 0.67945 0.3048)
			(end 0.120396 0.3048)
			(stroke
				(width 0.1)
				(type default)
			)
			(layer "F.Fab")
		)
		(fp_line
			(start -0.12065 0.2794)
			(end -0.12065 0.3048)
			(stroke
				(width 0.1)
				(type default)
			)
			(layer "F.Fab")
		)
		(fp_line
			(start 0.120396 0.2794)
			(end -0.12065 0.2794)
			(stroke
				(width 0.1)
				(type default)
			)
			(layer "F.Fab")
		)
		(fp_line
			(start -0.12065 -0.2794)
			(end 0.12065 -0.2794)
			(stroke
				(width 0.1)
				(type default)
			)
			(layer "F.Fab")
		)
		(fp_line
			(start 0.12065 -0.2794)
			(end 0.12065 -0.3048)
			(stroke
				(width 0.1)
				(type default)
			)
			(layer "F.Fab")
		)
		(fp_line
			(start 0.12065 -0.3048)
			(end 0.67945 -0.3048)
			(stroke
				(width 0.1)
				(type default)
			)
			(layer "F.Fab")
		)
		(fp_line
			(start 0.67945 -0.3048)
			(end 0.67945 0.3048)
			(stroke
				(width 0.1)
				(type default)
			)
			(layer "F.Fab")
		)
		(fp_line
			(start -0.67945 -0.305054)
			(end -0.12065 -0.305054)
			(stroke
				(width 0.1)
				(type default)
			)
			(layer "F.Fab")
		)
		(fp_line
			(start -0.12065 -0.305054)
			(end -0.12065 -0.2794)
			(stroke
				(width 0.1)
				(type default)
			)
			(layer "F.Fab")
		)
		(pad "1" smd circle
			(at -0.40005 0 270)
			(size 0 0)
			(layers "F.Cu" "F.Mask" "F.Paste")
			(net "P0V8_PEX2_LSET2")
		)
		(pad "2" smd circle
			(at 0.40005 0 270)
			(size 0 0)
			(layers "F.Cu" "F.Mask" "F.Paste")
			(net "GND")
		)
	)
	(footprint ""
		(layer "F.Cu")
		(at 117.706902 -282.421584 -90)
		(property "Reference" "PC81"
			(at 0 0 270)
			(layer "F.SilkS")
			(hide yes)
			(effects
				(font
					(size 1.27 1.27)
				)
			)
		)
		(property "Value" ""
			(at 0 0 270)
			(layer "F.Fab")
			(effects
				(font
					(size 1.27 1.27)
				)
			)
		)
		(duplicate_pad_numbers_are_jumpers no)
		(fp_line
			(start -0.7874 0.4064)
			(end -0.7874 -0.4064)
			(stroke
				(width 0.1524)
				(type default)
			)
			(layer "F.SilkS")
		)
		(fp_line
			(start 0.7874 0.4064)
			(end -0.7874 0.4064)
			(stroke
				(width 0.1524)
				(type default)
			)
			(layer "F.SilkS")
		)
		(fp_line
			(start -0.7874 -0.4064)
			(end 0.7874 -0.4064)
			(stroke
				(width 0.1524)
				(type default)
			)
			(layer "F.SilkS")
		)
		(fp_line
			(start 0.7874 -0.4064)
			(end 0.7874 0.4064)
			(stroke
				(width 0.1524)
				(type default)
			)
			(layer "F.SilkS")
		)
		(fp_line
			(start -0.67945 0.3048)
			(end -0.67945 -0.305054)
			(stroke
				(width 0.1)
				(type default)
			)
			(layer "F.Fab")
		)
		(fp_line
			(start -0.12065 0.3048)
			(end -0.67945 0.3048)
			(stroke
				(width 0.1)
				(type default)
			)
			(layer "F.Fab")
		)
		(fp_line
			(start 0.120396 0.3048)
			(end 0.120396 0.2794)
			(stroke
				(width 0.1)
				(type default)
			)
			(layer "F.Fab")
		)
		(fp_line
			(start 0.67945 0.3048)
			(end 0.120396 0.3048)
			(stroke
				(width 0.1)
				(type default)
			)
			(layer "F.Fab")
		)
		(fp_line
			(start -0.12065 0.2794)
			(end -0.12065 0.3048)
			(stroke
				(width 0.1)
				(type default)
			)
			(layer "F.Fab")
		)
		(fp_line
			(start 0.120396 0.2794)
			(end -0.12065 0.2794)
			(stroke
				(width 0.1)
				(type default)
			)
			(layer "F.Fab")
		)
		(fp_line
			(start -0.12065 -0.2794)
			(end 0.12065 -0.2794)
			(stroke
				(width 0.1)
				(type default)
			)
			(layer "F.Fab")
		)
		(fp_line
			(start 0.12065 -0.2794)
			(end 0.12065 -0.3048)
			(stroke
				(width 0.1)
				(type default)
			)
			(layer "F.Fab")
		)
		(fp_line
			(start 0.12065 -0.3048)
			(end 0.67945 -0.3048)
			(stroke
				(width 0.1)
				(type default)
			)
			(layer "F.Fab")
		)
		(fp_line
			(start 0.67945 -0.3048)
			(end 0.67945 0.3048)
			(stroke
				(width 0.1)
				(type default)
			)
			(layer "F.Fab")
		)
		(fp_line
			(start -0.67945 -0.305054)
			(end -0.12065 -0.305054)
			(stroke
				(width 0.1)
				(type default)
			)
			(layer "F.Fab")
		)
		(fp_line
			(start -0.12065 -0.305054)
			(end -0.12065 -0.2794)
			(stroke
				(width 0.1)
				(type default)
			)
			(layer "F.Fab")
		)
		(pad "1" smd circle
			(at -0.40005 0 270)
			(size 0 0)
			(layers "F.Cu" "F.Mask" "F.Paste")
			(net "P0V8_PEX0_VCC2")
		)
		(pad "2" smd circle
			(at 0.40005 0 270)
			(size 0 0)
			(layers "F.Cu" "F.Mask" "F.Paste")
			(net "GND")
		)
	)
	(footprint ""
		(layer "F.Cu")
		(at 26.405332 -258.582922 90)
		(property "Reference" "L97"
			(at 0 0 90)
			(layer "F.SilkS")
			(hide yes)
			(effects
				(font
					(size 1.27 1.27)
				)
			)
		)
		(property "Value" ""
			(at 0 0 90)
			(layer "F.Fab")
			(effects
				(font
					(size 1.27 1.27)
				)
			)
		)
		(duplicate_pad_numbers_are_jumpers no)
		(fp_line
			(start 1.63576 -0.8128)
			(end 1.63576 0.8128)
			(stroke
				(width 0.1524)
				(type default)
			)
			(layer "F.SilkS")
		)
		(fp_line
			(start -1.63576 -0.8128)
			(end 1.63576 -0.8128)
			(stroke
				(width 0.1524)
				(type default)
			)
			(layer "F.SilkS")
		)
		(fp_line
			(start -1.63576 -0.8128)
			(end -1.63576 0.8128)
			(stroke
				(width 0.1524)
				(type default)
			)
			(layer "F.SilkS")
		)
		(fp_line
			(start 1.63576 0.8128)
			(end -1.63576 0.8128)
			(stroke
				(width 0.1524)
				(type default)
			)
			(layer "F.SilkS")
		)
		(fp_line
			(start 1.560576 -0.738632)
			(end -1.56083 -0.738632)
			(stroke
				(width 0.1)
				(type default)
			)
			(layer "F.Fab")
		)
		(fp_line
			(start -1.56083 -0.738632)
			(end -1.56083 0.7366)
			(stroke
				(width 0.1)
				(type default)
			)
			(layer "F.Fab")
		)
		(fp_line
			(start 1.560576 0.7366)
			(end 1.560576 -0.738632)
			(stroke
				(width 0.1)
				(type default)
			)
			(layer "F.Fab")
		)
		(fp_line
			(start 1.524 0.7366)
			(end 1.560576 0.7366)
			(stroke
				(width 0.1)
				(type default)
			)
			(layer "F.Fab")
		)
		(fp_line
			(start -1.524 0.7366)
			(end 1.524 0.7366)
			(stroke
				(width 0.1)
				(type default)
			)
			(layer "F.Fab")
		)
		(fp_line
			(start -1.56083 0.7366)
			(end -1.524 0.7366)
			(stroke
				(width 0.1)
				(type default)
			)
			(layer "F.Fab")
		)
		(pad "1" smd rect
			(at -0.94996 0 270)
			(size 1.1176 1.3716)
			(layers "F.Cu" "F.Mask" "F.Paste")
			(net "P1V8_PLL0_PEX0")
		)
		(pad "2" smd rect
			(at 0.94996 0 270)
			(size 1.1176 1.3716)
			(layers "F.Cu" "F.Mask" "F.Paste")
			(net "P1V8_VDDA_PEX0")
		)
	)
	(footprint ""
		(layer "F.Cu")
		(at 32.470344 -252.356874 -90)
		(property "Reference" "R1204"
			(at 0 0 270)
			(layer "F.SilkS")
			(hide yes)
			(effects
				(font
					(size 1.27 1.27)
				)
			)
		)
		(property "Value" ""
			(at 0 0 270)
			(layer "F.Fab")
			(effects
				(font
					(size 1.27 1.27)
				)
			)
		)
		(duplicate_pad_numbers_are_jumpers no)
		(fp_line
			(start -0.7874 0.4064)
			(end -0.7874 -0.4064)
			(stroke
				(width 0.1524)
				(type default)
			)
			(layer "F.SilkS")
		)
		(fp_line
			(start 0.7874 0.4064)
			(end -0.7874 0.4064)
			(stroke
				(width 0.1524)
				(type default)
			)
			(layer "F.SilkS")
		)
		(fp_line
			(start -0.7874 -0.4064)
			(end 0.7874 -0.4064)
			(stroke
				(width 0.1524)
				(type default)
			)
			(layer "F.SilkS")
		)
		(fp_line
			(start 0.7874 -0.4064)
			(end 0.7874 0.4064)
			(stroke
				(width 0.1524)
				(type default)
			)
			(layer "F.SilkS")
		)
		(fp_line
			(start -0.67945 0.3048)
			(end -0.67945 -0.305054)
			(stroke
				(width 0.1)
				(type default)
			)
			(layer "F.Fab")
		)
		(fp_line
			(start -0.12065 0.3048)
			(end -0.67945 0.3048)
			(stroke
				(width 0.1)
				(type default)
			)
			(layer "F.Fab")
		)
		(fp_line
			(start 0.120396 0.3048)
			(end 0.120396 0.2794)
			(stroke
				(width 0.1)
				(type default)
			)
			(layer "F.Fab")
		)
		(fp_line
			(start 0.67945 0.3048)
			(end 0.120396 0.3048)
			(stroke
				(width 0.1)
				(type default)
			)
			(layer "F.Fab")
		)
		(fp_line
			(start -0.12065 0.2794)
			(end -0.12065 0.3048)
			(stroke
				(width 0.1)
				(type default)
			)
			(layer "F.Fab")
		)
		(fp_line
			(start 0.120396 0.2794)
			(end -0.12065 0.2794)
			(stroke
				(width 0.1)
				(type default)
			)
			(layer "F.Fab")
		)
		(fp_line
			(start -0.12065 -0.2794)
			(end 0.12065 -0.2794)
			(stroke
				(width 0.1)
				(type default)
			)
			(layer "F.Fab")
		)
		(fp_line
			(start 0.12065 -0.2794)
			(end 0.12065 -0.3048)
			(stroke
				(width 0.1)
				(type default)
			)
			(layer "F.Fab")
		)
		(fp_line
			(start 0.12065 -0.3048)
			(end 0.67945 -0.3048)
			(stroke
				(width 0.1)
				(type default)
			)
			(layer "F.Fab")
		)
		(fp_line
			(start 0.67945 -0.3048)
			(end 0.67945 0.3048)
			(stroke
				(width 0.1)
				(type default)
			)
			(layer "F.Fab")
		)
		(fp_line
			(start -0.67945 -0.305054)
			(end -0.12065 -0.305054)
			(stroke
				(width 0.1)
				(type default)
			)
			(layer "F.Fab")
		)
		(fp_line
			(start -0.12065 -0.305054)
			(end -0.12065 -0.2794)
			(stroke
				(width 0.1)
				(type default)
			)
			(layer "F.Fab")
		)
		(pad "1" smd circle
			(at -0.40005 0 270)
			(size 0 0)
			(layers "F.Cu" "F.Mask" "F.Paste")
			(net "GND")
		)
		(pad "2" smd circle
			(at 0.40005 0 270)
			(size 0 0)
			(layers "F.Cu" "F.Mask" "F.Paste")
			(net "PEX0_MODE_SEL8")
		)
	)
	(footprint ""
		(layer "F.Cu")
		(at 58.995056 -99.750372 180)
		(property "Reference" "R79"
			(at 0 0 180)
			(layer "F.SilkS")
			(hide yes)
			(effects
				(font
					(size 1.27 1.27)
				)
			)
		)
		(property "Value" ""
			(at 0 0 180)
			(layer "F.Fab")
			(effects
				(font
					(size 1.27 1.27)
				)
			)
		)
		(duplicate_pad_numbers_are_jumpers no)
		(fp_line
			(start 0.7874 0.4064)
			(end -0.7874 0.4064)
			(stroke
				(width 0.1524)
				(type default)
			)
			(layer "F.SilkS")
		)
		(fp_line
			(start 0.7874 -0.4064)
			(end 0.7874 0.4064)
			(stroke
				(width 0.1524)
				(type default)
			)
			(layer "F.SilkS")
		)
		(fp_line
			(start -0.7874 0.4064)
			(end -0.7874 -0.4064)
			(stroke
				(width 0.1524)
				(type default)
			)
			(layer "F.SilkS")
		)
		(fp_line
			(start -0.7874 -0.4064)
			(end 0.7874 -0.4064)
			(stroke
				(width 0.1524)
				(type default)
			)
			(layer "F.SilkS")
		)
		(fp_line
			(start 0.67945 0.3048)
			(end 0.120396 0.3048)
			(stroke
				(width 0.1)
				(type default)
			)
			(layer "F.Fab")
		)
		(fp_line
			(start 0.67945 -0.3048)
			(end 0.67945 0.3048)
			(stroke
				(width 0.1)
				(type default)
			)
			(layer "F.Fab")
		)
		(fp_line
			(start 0.12065 -0.2794)
			(end 0.12065 -0.3048)
			(stroke
				(width 0.1)
				(type default)
			)
			(layer "F.Fab")
		)
		(fp_line
			(start 0.12065 -0.3048)
			(end 0.67945 -0.3048)
			(stroke
				(width 0.1)
				(type default)
			)
			(layer "F.Fab")
		)
		(fp_line
			(start 0.120396 0.3048)
			(end 0.120396 0.2794)
			(stroke
				(width 0.1)
				(type default)
			)
			(layer "F.Fab")
		)
		(fp_line
			(start 0.120396 0.2794)
			(end -0.12065 0.2794)
			(stroke
				(width 0.1)
				(type default)
			)
			(layer "F.Fab")
		)
		(fp_line
			(start -0.12065 0.3048)
			(end -0.67945 0.3048)
			(stroke
				(width 0.1)
				(type default)
			)
			(layer "F.Fab")
		)
		(fp_line
			(start -0.12065 0.2794)
			(end -0.12065 0.3048)
			(stroke
				(width 0.1)
				(type default)
			)
			(layer "F.Fab")
		)
		(fp_line
			(start -0.12065 -0.2794)
			(end 0.12065 -0.2794)
			(stroke
				(width 0.1)
				(type default)
			)
			(layer "F.Fab")
		)
		(fp_line
			(start -0.12065 -0.305054)
			(end -0.12065 -0.2794)
			(stroke
				(width 0.1)
				(type default)
			)
			(layer "F.Fab")
		)
		(fp_line
			(start -0.67945 0.3048)
			(end -0.67945 -0.305054)
			(stroke
				(width 0.1)
				(type default)
			)
			(layer "F.Fab")
		)
		(fp_line
			(start -0.67945 -0.305054)
			(end -0.12065 -0.305054)
			(stroke
				(width 0.1)
				(type default)
			)
			(layer "F.Fab")
		)
		(pad "1" smd circle
			(at -0.40005 0 180)
			(size 0 0)
			(layers "F.Cu" "F.Mask" "F.Paste")
			(net "NIC1_SLOT_ID1")
		)
		(pad "2" smd circle
			(at 0.40005 0 180)
			(size 0 0)
			(layers "F.Cu" "F.Mask" "F.Paste")
			(net "GND")
		)
	)
)
